(kicad_pcb
	(version 20260206)
	(generator "pcbnew")
	(generator_version "10.0")
	(general
		(thickness 1.6)
		(legacy_teardrops no)
	)
	(paper "A4")
	(title_block
		(title "Bryce Canyon_IOM_M2_16342-2_OCP.brd")
		(comment 1 "Bryce Canyon / footprint 577 of 1146 (CN1), pads 1-74 of 202")
	)
	(layers
		(0 "F.Cu" signal "TOP")
		(4 "In1.Cu" signal "L2GND")
		(6 "In2.Cu" signal "L3")
		(8 "In3.Cu" signal "L4VCC")
		(10 "In4.Cu" signal "L5VCC")
		(12 "In5.Cu" signal "L6")
		(14 "In6.Cu" signal "L7GND")
		(2 "B.Cu" signal "BOTTOM")
		(9 "F.Adhes" user "F.Adhesive")
		(11 "B.Adhes" user "B.Adhesive")
		(13 "F.Paste" user "Package Geometry/Pastemask Top")
		(15 "B.Paste" user "Package Geometry/Pastemask Bottom")
		(5 "F.SilkS" user "Ref Des/Silkscreen Top")
		(7 "B.SilkS" user "Ref Des/Silkscreen Bottom")
		(1 "F.Mask" user "Board Geometry/Soldermask Top")
		(3 "B.Mask" user "Board Geometry/Soldermask Bottom")
		(17 "Dwgs.User" user "User.Drawings")
		(19 "Cmts.User" user "User.Comments")
		(21 "Eco1.User" user "User.Eco1")
		(23 "Eco2.User" user "User.Eco2")
		(25 "Edge.Cuts" user "Board Geometry/Outline")
		(27 "Margin" user)
		(31 "F.CrtYd" user "Package Geometry/Place Bound Top")
		(29 "B.CrtYd" user "Package Geometry/Place Bound Bottom")
		(35 "F.Fab" user "Ref Des/Assembly Top")
		(33 "B.Fab" user "Ref Des/Assembly Bottom")
	)
	(footprint ""
		(layer "F.Cu")
		(at 141.299946 -44.200064 180)
		(property "Reference" "CN1"
			(at 0 0 180)
			(layer "F.SilkS")
			(hide yes)
			(effects
				(font
					(size 1.27 1.27)
				)
			)
		)
		(property "Value" "AMP-CONN200-13R-4-GP"
			(at 30.332934 43.515534 180)
			(unlocked yes)
			(layer "F.Fab")
			(hide yes)
			(effects
				(font
					(size 1.016 1.016)
					(thickness 0.1524)
				)
			)
		)
		(property "Device Type" "PREFIT-200P-360520-1H542"
			(at 30.332934 41.991534 180)
			(unlocked yes)
			(layer "F.Fab")
			(hide yes)
			(effects
				(font
					(size 1.016 1.016)
					(thickness 0.1524)
				)
			)
		)
		(duplicate_pad_numbers_are_jumpers no)
		(pad "" np_thru_hole circle
			(at 17.135094 -9.344914 180)
			(size 0.254 0.254)
			(drill 2.4638)
			(layers "*.Cu" "*.Mask")
			(clearance 1.4605)
			(thermal_gap 1.4605)
		)
		(pad "" np_thru_hole circle
			(at 17.135094 -2.355088 180)
			(size 0.254 0.254)
			(drill 2.3876)
			(layers "*.Cu" "*.Mask")
			(clearance 1.4224)
			(thermal_gap 1.4224)
		)
		(pad "A1" thru_hole circle
			(at 0 0 180)
			(size 0.762 0.762)
			(drill 0.359918)
			(layers "*.Cu" "*.Mask")
			(remove_unused_layers no)
			(net "PCIE_COMP_TO_IOM_CLK_2_DN")
			(clearance 0.1651)
			(thermal_gap 0.1651)
		)
		(pad "A2" thru_hole circle
			(at 1.800098 1.199896 180)
			(size 0.762 0.762)
			(drill 0.359918)
			(layers "*.Cu" "*.Mask")
			(remove_unused_layers no)
			(net "I2C_DPB_MISC_SDA")
			(clearance 0.1651)
			(thermal_gap 0.1651)
		)
		(pad "A3" thru_hole circle
			(at 3.599942 0 180)
			(size 0.762 0.762)
			(drill 0.359918)
			(layers "*.Cu" "*.Mask")
			(remove_unused_layers no)
			(net "BMC_LOC_HEARTBEAT")
			(clearance 0.1651)
			(thermal_gap 0.1651)
		)
		(pad "A4" thru_hole circle
			(at 5.40004 1.199896 180)
			(size 0.762 0.762)
			(drill 0.359918)
			(layers "*.Cu" "*.Mask")
			(remove_unused_layers no)
			(net "SCC_RMT_FULL_PWR_EN")
			(clearance 0.1651)
			(thermal_gap 0.1651)
		)
		(pad "A5" thru_hole circle
			(at 7.199884 0 180)
			(size 0.762 0.762)
			(drill 0.359918)
			(layers "*.Cu" "*.Mask")
			(remove_unused_layers no)
			(net "PCIE_COMP_TO_IOM_CLK_3_DN")
			(clearance 0.1651)
			(thermal_gap 0.1651)
		)
		(pad "A6" thru_hole circle
			(at 8.999982 1.199896 180)
			(size 0.762 0.762)
			(drill 0.359918)
			(layers "*.Cu" "*.Mask")
			(remove_unused_layers no)
			(net "I2C_EXP_LOC_SDA")
			(clearance 0.1651)
			(thermal_gap 0.1651)
		)
		(pad "A7" thru_hole circle
			(at 10.80008 0 180)
			(size 0.762 0.762)
			(drill 0.359918)
			(layers "*.Cu" "*.Mask")
			(remove_unused_layers no)
			(net "P12V_IOM")
			(clearance 0.1651)
			(thermal_gap 0.1651)
		)
		(pad "A8" thru_hole circle
			(at 12.599924 1.199896 180)
			(size 0.762 0.762)
			(drill 0.359918)
			(layers "*.Cu" "*.Mask")
			(remove_unused_layers no)
			(net "P12V_IOM")
			(clearance 0.1651)
			(thermal_gap 0.1651)
		)
		(pad "A9" thru_hole circle
			(at 21.599906 0 180)
			(size 0.762 0.762)
			(drill 0.359918)
			(layers "*.Cu" "*.Mask")
			(remove_unused_layers no)
			(net "PCIE_COMP_TO_IOM_CLK_4_DN")
			(clearance 0.1651)
			(thermal_gap 0.1651)
		)
		(pad "A10" thru_hole circle
			(at 23.400004 1.199896 180)
			(size 0.762 0.762)
			(drill 0.359918)
			(layers "*.Cu" "*.Mask")
			(remove_unused_layers no)
			(net "SLOTID_1")
			(clearance 0.1651)
			(thermal_gap 0.1651)
		)
		(pad "A11" thru_hole circle
			(at 25.200102 0 180)
			(size 0.762 0.762)
			(drill 0.359918)
			(layers "*.Cu" "*.Mask")
			(remove_unused_layers no)
			(net "BMC_TO_EXP_RESET_N")
			(clearance 0.1651)
			(thermal_gap 0.1651)
		)
		(pad "A12" thru_hole circle
			(at 26.999946 1.199896 180)
			(size 0.762 0.762)
			(drill 0.359918)
			(layers "*.Cu" "*.Mask")
			(remove_unused_layers no)
			(net "USB_COMP_DN")
			(clearance 0.1651)
			(thermal_gap 0.1651)
		)
		(pad "A13" thru_hole circle
			(at 28.800044 0 180)
			(size 0.762 0.762)
			(drill 0.359918)
			(layers "*.Cu" "*.Mask")
			(remove_unused_layers no)
			(net "COMP_TO_BMC_RESET")
			(clearance 0.1651)
			(thermal_gap 0.1651)
		)
		(pad "A14" thru_hole circle
			(at 30.599888 1.199896 180)
			(size 0.762 0.762)
			(drill 0.359918)
			(layers "*.Cu" "*.Mask")
			(remove_unused_layers no)
			(net "I2C_DPB_SDA")
			(clearance 0.1651)
			(thermal_gap 0.1651)
		)
		(pad "A15" thru_hole circle
			(at 32.399986 0 180)
			(size 0.762 0.762)
			(drill 0.359918)
			(layers "*.Cu" "*.Mask")
			(remove_unused_layers no)
			(net "EXP_SPARE_1")
			(clearance 0.1651)
			(thermal_gap 0.1651)
		)
		(pad "A16" thru_hole circle
			(at 34.200084 1.199896 180)
			(size 0.762 0.762)
			(drill 0.359918)
			(layers "*.Cu" "*.Mask")
			(remove_unused_layers no)
			(net "COMP_SPARE_1")
			(clearance 0.1651)
			(thermal_gap 0.1651)
		)
		(pad "B1" thru_hole circle
			(at 0 -1.400048 180)
			(size 0.762 0.762)
			(drill 0.359918)
			(layers "*.Cu" "*.Mask")
			(remove_unused_layers no)
			(net "PCIE_COMP_TO_IOM_CLK_2_DP")
			(clearance 0.1651)
			(thermal_gap 0.1651)
		)
		(pad "B2" thru_hole circle
			(at 1.800098 -0.199898 180)
			(size 0.762 0.762)
			(drill 0.359918)
			(layers "*.Cu" "*.Mask")
			(remove_unused_layers no)
			(net "I2C_DPB_MISC_SCL")
			(clearance 0.1651)
			(thermal_gap 0.1651)
		)
		(pad "B3" thru_hole circle
			(at 3.599942 -1.400048 180)
			(size 0.762 0.762)
			(drill 0.359918)
			(layers "*.Cu" "*.Mask")
			(remove_unused_layers no)
			(net "BMC_RMT_HEARTBEAT")
			(clearance 0.1651)
			(thermal_gap 0.1651)
		)
		(pad "B4" thru_hole circle
			(at 5.40004 -0.199898 180)
			(size 0.762 0.762)
			(drill 0.359918)
			(layers "*.Cu" "*.Mask")
			(remove_unused_layers no)
			(net "SCC_LOC_FULL_PWR_EN")
			(clearance 0.1651)
			(thermal_gap 0.1651)
		)
		(pad "B5" thru_hole circle
			(at 7.199884 -1.400048 180)
			(size 0.762 0.762)
			(drill 0.359918)
			(layers "*.Cu" "*.Mask")
			(remove_unused_layers no)
			(net "PCIE_COMP_TO_IOM_CLK_3_DP")
			(clearance 0.1651)
			(thermal_gap 0.1651)
		)
		(pad "B6" thru_hole circle
			(at 8.999982 -0.199898 180)
			(size 0.762 0.762)
			(drill 0.359918)
			(layers "*.Cu" "*.Mask")
			(remove_unused_layers no)
			(net "I2C_EXP_LOC_SCL")
			(clearance 0.1651)
			(thermal_gap 0.1651)
		)
		(pad "B7" thru_hole circle
			(at 10.80008 -1.400048 180)
			(size 0.762 0.762)
			(drill 0.359918)
			(layers "*.Cu" "*.Mask")
			(remove_unused_layers no)
			(net "P12V_A_PGOOD")
			(clearance 0.1651)
			(thermal_gap 0.1651)
		)
		(pad "B8" thru_hole circle
			(at 12.599924 -0.199898 180)
			(size 0.762 0.762)
			(drill 0.359918)
			(layers "*.Cu" "*.Mask")
			(remove_unused_layers no)
			(net "P12V_IOM")
			(clearance 0.1651)
			(thermal_gap 0.1651)
		)
		(pad "B9" thru_hole circle
			(at 21.599906 -1.400048 180)
			(size 0.762 0.762)
			(drill 0.359918)
			(layers "*.Cu" "*.Mask")
			(remove_unused_layers no)
			(net "PCIE_COMP_TO_IOM_CLK_4_DP")
			(clearance 0.1651)
			(thermal_gap 0.1651)
		)
		(pad "B10" thru_hole circle
			(at 23.400004 -0.199898 180)
			(size 0.762 0.762)
			(drill 0.359918)
			(layers "*.Cu" "*.Mask")
			(remove_unused_layers no)
			(net "SLOTID_0")
			(clearance 0.1651)
			(thermal_gap 0.1651)
		)
		(pad "B11" thru_hole circle
			(at 25.200102 -1.400048 180)
			(size 0.762 0.762)
			(drill 0.359918)
			(layers "*.Cu" "*.Mask")
			(remove_unused_layers no)
			(net "DPB_MISC_ALERT")
			(clearance 0.1651)
			(thermal_gap 0.1651)
		)
		(pad "B12" thru_hole circle
			(at 26.999946 -0.199898 180)
			(size 0.762 0.762)
			(drill 0.359918)
			(layers "*.Cu" "*.Mask")
			(remove_unused_layers no)
			(net "USB_COMP_DP")
			(clearance 0.1651)
			(thermal_gap 0.1651)
		)
		(pad "B13" thru_hole circle
			(at 28.800044 -1.400048 180)
			(size 0.762 0.762)
			(drill 0.359918)
			(layers "*.Cu" "*.Mask")
			(remove_unused_layers no)
			(net "SYS_RESET_N")
			(clearance 0.1651)
			(thermal_gap 0.1651)
		)
		(pad "B14" thru_hole circle
			(at 30.599888 -0.199898 180)
			(size 0.762 0.762)
			(drill 0.359918)
			(layers "*.Cu" "*.Mask")
			(remove_unused_layers no)
			(net "I2C_DPB_SCL")
			(clearance 0.1651)
			(thermal_gap 0.1651)
		)
		(pad "B15" thru_hole circle
			(at 32.399986 -1.400048 180)
			(size 0.762 0.762)
			(drill 0.359918)
			(layers "*.Cu" "*.Mask")
			(remove_unused_layers no)
			(net "EXP_SPARE_0")
			(clearance 0.1651)
			(thermal_gap 0.1651)
		)
		(pad "B16" thru_hole circle
			(at 34.200084 -0.199898 180)
			(size 0.762 0.762)
			(drill 0.359918)
			(layers "*.Cu" "*.Mask")
			(remove_unused_layers no)
			(net "COMP_SPARE_0")
			(clearance 0.1651)
			(thermal_gap 0.1651)
		)
		(pad "C1" thru_hole circle
			(at 0 -3.599942 180)
			(size 0.762 0.762)
			(drill 0.359918)
			(layers "*.Cu" "*.Mask")
			(remove_unused_layers no)
			(net "IOM_MATED_N")
			(clearance 0.1651)
			(thermal_gap 0.1651)
		)
		(pad "C2" thru_hole circle
			(at 1.800098 -2.400046 180)
			(size 0.762 0.762)
			(drill 0.359918)
			(layers "*.Cu" "*.Mask")
			(remove_unused_layers no)
			(net "I2C_SCC_SDA")
			(clearance 0.1651)
			(thermal_gap 0.1651)
		)
		(pad "C3" thru_hole circle
			(at 3.599942 -3.599942 180)
			(size 0.762 0.762)
			(drill 0.359918)
			(layers "*.Cu" "*.Mask")
			(remove_unused_layers no)
			(net "SCC_RMT_HEARTBEAT")
			(clearance 0.1651)
			(thermal_gap 0.1651)
		)
		(pad "C4" thru_hole circle
			(at 5.40004 -2.400046 180)
			(size 0.762 0.762)
			(drill 0.359918)
			(layers "*.Cu" "*.Mask")
			(remove_unused_layers no)
			(net "SYS_PWR_LED")
			(clearance 0.1651)
			(thermal_gap 0.1651)
		)
		(pad "C5" thru_hole circle
			(at 7.199884 -3.599942 180)
			(size 0.762 0.762)
			(drill 0.359918)
			(layers "*.Cu" "*.Mask")
			(remove_unused_layers no)
			(net "IOM_LOC_INS_N")
			(clearance 0.1651)
			(thermal_gap 0.1651)
		)
		(pad "C6" thru_hole circle
			(at 8.999982 -2.400046 180)
			(size 0.762 0.762)
			(drill 0.359918)
			(layers "*.Cu" "*.Mask")
			(remove_unused_layers no)
			(net "I2C_EXP_RMT_SDA")
			(clearance 0.1651)
			(thermal_gap 0.1651)
		)
		(pad "C7" thru_hole circle
			(at 10.80008 -3.599942 180)
			(size 0.762 0.762)
			(drill 0.359918)
			(layers "*.Cu" "*.Mask")
			(remove_unused_layers no)
			(net "UART_SDB_RX")
			(clearance 0.1651)
			(thermal_gap 0.1651)
		)
		(pad "C8" thru_hole circle
			(at 12.599924 -2.400046 180)
			(size 0.762 0.762)
			(drill 0.359918)
			(layers "*.Cu" "*.Mask")
			(remove_unused_layers no)
			(net "P12V_IOM")
			(clearance 0.1651)
			(thermal_gap 0.1651)
		)
		(pad "C9" thru_hole circle
			(at 21.599906 -3.599942 180)
			(size 0.762 0.762)
			(drill 0.359918)
			(layers "*.Cu" "*.Mask")
			(remove_unused_layers no)
			(net "I2C_BMC_COMP_ALERT_N")
			(clearance 0.1651)
			(thermal_gap 0.1651)
		)
		(pad "C10" thru_hole circle
			(at 23.400004 -2.400046 180)
			(size 0.762 0.762)
			(drill 0.359918)
			(layers "*.Cu" "*.Mask")
			(remove_unused_layers no)
			(net "I2C_BMC_COMP_SDA")
			(clearance 0.1651)
			(thermal_gap 0.1651)
		)
		(pad "C11" thru_hole circle
			(at 25.200102 -3.599942 180)
			(size 0.762 0.762)
			(drill 0.359918)
			(layers "*.Cu" "*.Mask")
			(remove_unused_layers no)
			(net "UART_COMP_RX")
			(clearance 0.1651)
			(thermal_gap 0.1651)
		)
		(pad "C12" thru_hole circle
			(at 26.999946 -2.400046 180)
			(size 0.762 0.762)
			(drill 0.359918)
			(layers "*.Cu" "*.Mask")
			(remove_unused_layers no)
			(net "COMP_PWR_EN")
			(clearance 0.1651)
			(thermal_gap 0.1651)
		)
		(pad "C13" thru_hole circle
			(at 28.800044 -3.599942 180)
			(size 0.762 0.762)
			(drill 0.359918)
			(layers "*.Cu" "*.Mask")
			(remove_unused_layers no)
			(net "COMP_POWER_FAIL_N")
			(clearance 0.1651)
			(thermal_gap 0.1651)
		)
		(pad "C14" thru_hole circle
			(at 30.599888 -2.400046 180)
			(size 0.762 0.762)
			(drill 0.359918)
			(layers "*.Cu" "*.Mask")
			(remove_unused_layers no)
			(net "Net_79")
			(clearance 0.1651)
			(thermal_gap 0.1651)
		)
		(pad "C15" thru_hole circle
			(at 32.399986 -3.599942 180)
			(size 0.762 0.762)
			(drill 0.359918)
			(layers "*.Cu" "*.Mask")
			(remove_unused_layers no)
			(net "Net_190")
			(clearance 0.1651)
			(thermal_gap 0.1651)
		)
		(pad "C16" thru_hole circle
			(at 34.200084 -2.400046 180)
			(size 0.762 0.762)
			(drill 0.359918)
			(layers "*.Cu" "*.Mask")
			(remove_unused_layers no)
			(net "PWM_OUT_ZONE_C")
			(clearance 0.1651)
			(thermal_gap 0.1651)
		)
		(pad "D1" thru_hole circle
			(at 0 -4.99999 180)
			(size 0.762 0.762)
			(drill 0.359918)
			(layers "*.Cu" "*.Mask")
			(remove_unused_layers no)
			(net "PCIE_COMP_TO_IOM_RST_2")
			(clearance 0.1651)
			(thermal_gap 0.1651)
		)
		(pad "D2" thru_hole circle
			(at 1.800098 -3.800094 180)
			(size 0.762 0.762)
			(drill 0.359918)
			(layers "*.Cu" "*.Mask")
			(remove_unused_layers no)
			(net "I2C_SCC_SCL")
			(clearance 0.1651)
			(thermal_gap 0.1651)
		)
		(pad "D3" thru_hole circle
			(at 3.599942 -4.99999 180)
			(size 0.762 0.762)
			(drill 0.359918)
			(layers "*.Cu" "*.Mask")
			(remove_unused_layers no)
			(net "SCC_LOC_HEARTBEAT")
			(clearance 0.1651)
			(thermal_gap 0.1651)
		)
		(pad "D4" thru_hole circle
			(at 5.40004 -3.800094 180)
			(size 0.762 0.762)
			(drill 0.359918)
			(layers "*.Cu" "*.Mask")
			(remove_unused_layers no)
			(net "SCC_STBY_PWR_EN")
			(clearance 0.1651)
			(thermal_gap 0.1651)
		)
		(pad "D5" thru_hole circle
			(at 7.199884 -4.99999 180)
			(size 0.762 0.762)
			(drill 0.359918)
			(layers "*.Cu" "*.Mask")
			(remove_unused_layers no)
			(net "PCIE_COMP_TO_IOM_RST_3")
			(clearance 0.1651)
			(thermal_gap 0.1651)
		)
		(pad "D6" thru_hole circle
			(at 8.999982 -3.800094 180)
			(size 0.762 0.762)
			(drill 0.359918)
			(layers "*.Cu" "*.Mask")
			(remove_unused_layers no)
			(net "I2C_EXP_RMT_SCL")
			(clearance 0.1651)
			(thermal_gap 0.1651)
		)
		(pad "D7" thru_hole circle
			(at 10.80008 -4.99999 180)
			(size 0.762 0.762)
			(drill 0.359918)
			(layers "*.Cu" "*.Mask")
			(remove_unused_layers no)
			(net "UART_SDB_TX")
			(clearance 0.1651)
			(thermal_gap 0.1651)
		)
		(pad "D8" thru_hole circle
			(at 12.599924 -3.800094 180)
			(size 0.762 0.762)
			(drill 0.359918)
			(layers "*.Cu" "*.Mask")
			(remove_unused_layers no)
			(net "P12V_IOM")
			(clearance 0.1651)
			(thermal_gap 0.1651)
		)
		(pad "D9" thru_hole circle
			(at 21.599906 -4.99999 180)
			(size 0.762 0.762)
			(drill 0.359918)
			(layers "*.Cu" "*.Mask")
			(remove_unused_layers no)
			(net "PCIE_COMP_TO_IOM_RST_4")
			(clearance 0.1651)
			(thermal_gap 0.1651)
		)
		(pad "D10" thru_hole circle
			(at 23.400004 -3.800094 180)
			(size 0.762 0.762)
			(drill 0.359918)
			(layers "*.Cu" "*.Mask")
			(remove_unused_layers no)
			(net "I2C_BMC_COMP_SCL")
			(clearance 0.1651)
			(thermal_gap 0.1651)
		)
		(pad "D11" thru_hole circle
			(at 25.200102 -4.99999 180)
			(size 0.762 0.762)
			(drill 0.359918)
			(layers "*.Cu" "*.Mask")
			(remove_unused_layers no)
			(net "UART_COMP_TX")
			(clearance 0.1651)
			(thermal_gap 0.1651)
		)
		(pad "D12" thru_hole circle
			(at 26.999946 -3.800094 180)
			(size 0.762 0.762)
			(drill 0.359918)
			(layers "*.Cu" "*.Mask")
			(remove_unused_layers no)
			(net "SCC_RMT_TYPE_0")
			(clearance 0.1651)
			(thermal_gap 0.1651)
		)
		(pad "D13" thru_hole circle
			(at 28.800044 -4.99999 180)
			(size 0.762 0.762)
			(drill 0.359918)
			(layers "*.Cu" "*.Mask")
			(remove_unused_layers no)
			(net "COMP_FAST_THROTTLE_N")
			(clearance 0.1651)
			(thermal_gap 0.1651)
		)
		(pad "D14" thru_hole circle
			(at 30.599888 -3.800094 180)
			(size 0.762 0.762)
			(drill 0.359918)
			(layers "*.Cu" "*.Mask")
			(remove_unused_layers no)
			(net "COMP_PWR_BTN_N")
			(clearance 0.1651)
			(thermal_gap 0.1651)
		)
		(pad "D15" thru_hole circle
			(at 32.399986 -4.99999 180)
			(size 0.762 0.762)
			(drill 0.359918)
			(layers "*.Cu" "*.Mask")
			(remove_unused_layers no)
			(net "ENCL_FAULT_LED")
			(clearance 0.1651)
			(thermal_gap 0.1651)
		)
		(pad "D16" thru_hole circle
			(at 34.200084 -3.800094 180)
			(size 0.762 0.762)
			(drill 0.359918)
			(layers "*.Cu" "*.Mask")
			(remove_unused_layers no)
			(net "PWM_OUT_ZONE_D")
			(clearance 0.1651)
			(thermal_gap 0.1651)
		)
		(pad "E1" thru_hole circle
			(at 0 -7.199884 180)
			(size 0.762 0.762)
			(drill 0.359918)
			(layers "*.Cu" "*.Mask")
			(remove_unused_layers no)
			(net "PCIE_IOM_TO_COMP_8_DN")
			(clearance 0.1651)
			(thermal_gap 0.1651)
		)
		(pad "E2" thru_hole circle
			(at 1.800098 -5.999988 180)
			(size 0.762 0.762)
			(drill 0.359918)
			(layers "*.Cu" "*.Mask")
			(remove_unused_layers no)
			(net "PCIE_IOM_TO_COMP_9_DN")
			(clearance 0.1651)
			(thermal_gap 0.1651)
		)
		(pad "E3" thru_hole circle
			(at 3.599942 -7.199884 180)
			(size 0.762 0.762)
			(drill 0.359918)
			(layers "*.Cu" "*.Mask")
			(remove_unused_layers no)
			(net "PCIE_IOM_TO_COMP_10_DN")
			(clearance 0.1651)
			(thermal_gap 0.1651)
		)
		(pad "E4" thru_hole circle
			(at 5.40004 -5.999988 180)
			(size 0.762 0.762)
			(drill 0.359918)
			(layers "*.Cu" "*.Mask")
			(remove_unused_layers no)
			(net "PCIE_IOM_TO_COMP_11_DN")
			(clearance 0.1651)
			(thermal_gap 0.1651)
		)
		(pad "E5" thru_hole circle
			(at 7.199884 -7.199884 180)
			(size 0.762 0.762)
			(drill 0.359918)
			(layers "*.Cu" "*.Mask")
			(remove_unused_layers no)
			(net "PCIE_IOM_TO_COMP_12_DN")
			(clearance 0.1651)
			(thermal_gap 0.1651)
		)
		(pad "E6" thru_hole circle
			(at 8.999982 -5.999988 180)
			(size 0.762 0.762)
			(drill 0.359918)
			(layers "*.Cu" "*.Mask")
			(remove_unused_layers no)
			(net "PCIE_IOM_TO_COMP_13_DN")
			(clearance 0.1651)
			(thermal_gap 0.1651)
		)
		(pad "E7" thru_hole circle
			(at 10.80008 -7.199884 180)
			(size 0.762 0.762)
			(drill 0.359918)
			(layers "*.Cu" "*.Mask")
			(remove_unused_layers no)
			(net "PCIE_IOM_TO_COMP_14_DN")
			(clearance 0.1651)
			(thermal_gap 0.1651)
		)
		(pad "E8" thru_hole circle
			(at 12.599924 -5.999988 180)
			(size 0.762 0.762)
			(drill 0.359918)
			(layers "*.Cu" "*.Mask")
			(remove_unused_layers no)
			(net "PCIE_IOM_TO_COMP_15_DN")
			(clearance 0.1651)
			(thermal_gap 0.1651)
		)
	)
)
